(kicad_pcb
	(version 20260206)
	(generator "pcbnew")
	(generator_version "10.0")
	(general
		(thickness 1.6)
		(legacy_teardrops no)
	)
	(paper "A4")
	(title_block
		(title "03242023_DA0F0TMBIJ0_F0T_Motherboard_J_brd_V01_OCP.brd")
		(comment 1 "Grand Teton / footprints 1365-1367 of 6105")
	)
	(layers
		(0 "F.Cu" signal "TOP")
		(4 "In1.Cu" signal "GND")
		(6 "In2.Cu" signal "IN1")
		(8 "In3.Cu" signal "GND1")
		(10 "In4.Cu" signal "IN2")
		(12 "In5.Cu" signal "GND2")
		(14 "In6.Cu" signal "IN3")
		(16 "In7.Cu" signal "GND3")
		(18 "In8.Cu" signal "VCC")
		(20 "In9.Cu" signal "VCC1")
		(22 "In10.Cu" signal "GND4")
		(24 "In11.Cu" signal "IN4")
		(26 "In12.Cu" signal "GND5")
		(28 "In13.Cu" signal "IN5")
		(30 "In14.Cu" signal "GND6")
		(32 "In15.Cu" signal "IN6")
		(34 "In16.Cu" signal "GND7")
		(2 "B.Cu" signal "BOTTOM")
		(9 "F.Adhes" user "F.Adhesive")
		(11 "B.Adhes" user "B.Adhesive")
		(13 "F.Paste" user "Package Geometry/Pastemask Top")
		(15 "B.Paste" user "Package Geometry/Pastemask Bottom")
		(5 "F.SilkS" user "Ref Des/Silkscreen Top")
		(7 "B.SilkS" user "Ref Des/Silkscreen Bottom")
		(1 "F.Mask" user "Board Geometry/Soldermask Top")
		(3 "B.Mask" user "Board Geometry/Soldermask Bottom")
		(17 "Dwgs.User" user "User.Drawings")
		(19 "Cmts.User" user "User.Comments")
		(21 "Eco1.User" user "User.Eco1")
		(23 "Eco2.User" user "User.Eco2")
		(25 "Edge.Cuts" user "Board Geometry/Outline")
		(27 "Margin" user)
		(31 "F.CrtYd" user "Package Geometry/Place Bound Top")
		(29 "B.CrtYd" user "Package Geometry/Place Bound Bottom")
		(35 "F.Fab" user "Ref Des/Assembly Top")
		(33 "B.Fab" user "Ref Des/Assembly Bottom")
	)
	(footprint ""
		(layer "F.Cu")
		(at 456.444858 -387.950964)
		(property "Reference" "PC1848"
			(at 0 0 0)
			(layer "F.SilkS")
			(hide yes)
			(effects
				(font
					(size 1.27 1.27)
				)
			)
		)
		(property "Value" ""
			(at 0 0 0)
			(layer "F.Fab")
			(effects
				(font
					(size 1.27 1.27)
				)
			)
		)
		(duplicate_pad_numbers_are_jumpers no)
		(fp_line
			(start -0.7874 -0.4064)
			(end 0.7874 -0.4064)
			(stroke
				(width 0.1524)
				(type default)
			)
			(layer "F.SilkS")
		)
		(fp_line
			(start -0.7874 0.4064)
			(end -0.7874 -0.4064)
			(stroke
				(width 0.1524)
				(type default)
			)
			(layer "F.SilkS")
		)
		(fp_line
			(start 0.7874 -0.4064)
			(end 0.7874 0.4064)
			(stroke
				(width 0.1524)
				(type default)
			)
			(layer "F.SilkS")
		)
		(fp_line
			(start 0.7874 0.4064)
			(end -0.7874 0.4064)
			(stroke
				(width 0.1524)
				(type default)
			)
			(layer "F.SilkS")
		)
		(fp_line
			(start -0.67945 -0.305054)
			(end -0.12065 -0.305054)
			(stroke
				(width 0.1)
				(type default)
			)
			(layer "F.Fab")
		)
		(fp_line
			(start -0.67945 0.3048)
			(end -0.67945 -0.305054)
			(stroke
				(width 0.1)
				(type default)
			)
			(layer "F.Fab")
		)
		(fp_line
			(start -0.12065 -0.305054)
			(end -0.12065 -0.2794)
			(stroke
				(width 0.1)
				(type default)
			)
			(layer "F.Fab")
		)
		(fp_line
			(start -0.12065 -0.2794)
			(end 0.12065 -0.2794)
			(stroke
				(width 0.1)
				(type default)
			)
			(layer "F.Fab")
		)
		(fp_line
			(start -0.12065 0.2794)
			(end -0.12065 0.3048)
			(stroke
				(width 0.1)
				(type default)
			)
			(layer "F.Fab")
		)
		(fp_line
			(start -0.12065 0.3048)
			(end -0.67945 0.3048)
			(stroke
				(width 0.1)
				(type default)
			)
			(layer "F.Fab")
		)
		(fp_line
			(start 0.120396 0.2794)
			(end -0.12065 0.2794)
			(stroke
				(width 0.1)
				(type default)
			)
			(layer "F.Fab")
		)
		(fp_line
			(start 0.120396 0.3048)
			(end 0.120396 0.2794)
			(stroke
				(width 0.1)
				(type default)
			)
			(layer "F.Fab")
		)
		(fp_line
			(start 0.12065 -0.3048)
			(end 0.67945 -0.3048)
			(stroke
				(width 0.1)
				(type default)
			)
			(layer "F.Fab")
		)
		(fp_line
			(start 0.12065 -0.2794)
			(end 0.12065 -0.3048)
			(stroke
				(width 0.1)
				(type default)
			)
			(layer "F.Fab")
		)
		(fp_line
			(start 0.67945 -0.3048)
			(end 0.67945 0.3048)
			(stroke
				(width 0.1)
				(type default)
			)
			(layer "F.Fab")
		)
		(fp_line
			(start 0.67945 0.3048)
			(end 0.120396 0.3048)
			(stroke
				(width 0.1)
				(type default)
			)
			(layer "F.Fab")
		)
		(pad "1" smd circle
			(at -0.40005 0)
			(size 0 0)
			(layers "F.Cu" "F.Mask" "F.Paste")
			(net "P5V_AUX_VCC")
		)
		(pad "2" smd circle
			(at 0.40005 0)
			(size 0 0)
			(layers "F.Cu" "F.Mask" "F.Paste")
			(net "GND")
		)
	)
	(footprint ""
		(layer "F.Cu")
		(at 131.32308 -122.542808 -90)
		(property "Reference" "R3155"
			(at 0 0 270)
			(layer "F.SilkS")
			(hide yes)
			(effects
				(font
					(size 1.27 1.27)
				)
			)
		)
		(property "Value" ""
			(at 0 0 270)
			(layer "F.Fab")
			(effects
				(font
					(size 1.27 1.27)
				)
			)
		)
		(duplicate_pad_numbers_are_jumpers no)
		(fp_line
			(start -0.7874 0.4064)
			(end -0.7874 -0.4064)
			(stroke
				(width 0.1524)
				(type default)
			)
			(layer "F.SilkS")
		)
		(fp_line
			(start 0.7874 0.4064)
			(end -0.7874 0.4064)
			(stroke
				(width 0.1524)
				(type default)
			)
			(layer "F.SilkS")
		)
		(fp_line
			(start -0.7874 -0.4064)
			(end 0.7874 -0.4064)
			(stroke
				(width 0.1524)
				(type default)
			)
			(layer "F.SilkS")
		)
		(fp_line
			(start 0.7874 -0.4064)
			(end 0.7874 0.4064)
			(stroke
				(width 0.1524)
				(type default)
			)
			(layer "F.SilkS")
		)
		(fp_line
			(start -0.67945 0.3048)
			(end -0.67945 -0.305054)
			(stroke
				(width 0.1)
				(type default)
			)
			(layer "F.Fab")
		)
		(fp_line
			(start -0.12065 0.3048)
			(end -0.67945 0.3048)
			(stroke
				(width 0.1)
				(type default)
			)
			(layer "F.Fab")
		)
		(fp_line
			(start 0.120396 0.3048)
			(end 0.120396 0.2794)
			(stroke
				(width 0.1)
				(type default)
			)
			(layer "F.Fab")
		)
		(fp_line
			(start 0.67945 0.3048)
			(end 0.120396 0.3048)
			(stroke
				(width 0.1)
				(type default)
			)
			(layer "F.Fab")
		)
		(fp_line
			(start -0.12065 0.2794)
			(end -0.12065 0.3048)
			(stroke
				(width 0.1)
				(type default)
			)
			(layer "F.Fab")
		)
		(fp_line
			(start 0.120396 0.2794)
			(end -0.12065 0.2794)
			(stroke
				(width 0.1)
				(type default)
			)
			(layer "F.Fab")
		)
		(fp_line
			(start -0.12065 -0.2794)
			(end 0.12065 -0.2794)
			(stroke
				(width 0.1)
				(type default)
			)
			(layer "F.Fab")
		)
		(fp_line
			(start 0.12065 -0.2794)
			(end 0.12065 -0.3048)
			(stroke
				(width 0.1)
				(type default)
			)
			(layer "F.Fab")
		)
		(fp_line
			(start 0.12065 -0.3048)
			(end 0.67945 -0.3048)
			(stroke
				(width 0.1)
				(type default)
			)
			(layer "F.Fab")
		)
		(fp_line
			(start 0.67945 -0.3048)
			(end 0.67945 0.3048)
			(stroke
				(width 0.1)
				(type default)
			)
			(layer "F.Fab")
		)
		(fp_line
			(start -0.67945 -0.305054)
			(end -0.12065 -0.305054)
			(stroke
				(width 0.1)
				(type default)
			)
			(layer "F.Fab")
		)
		(fp_line
			(start -0.12065 -0.305054)
			(end -0.12065 -0.2794)
			(stroke
				(width 0.1)
				(type default)
			)
			(layer "F.Fab")
		)
		(pad "1" smd circle
			(at -0.40005 0 270)
			(size 0 0)
			(layers "F.Cu" "F.Mask" "F.Paste")
			(net "P3V3_AUX")
		)
		(pad "2" smd circle
			(at 0.40005 0 270)
			(size 0 0)
			(layers "F.Cu" "F.Mask" "F.Paste")
			(net "HP_LVC3_OCP_V3_2_PRSNT2")
		)
	)
	(footprint ""
		(layer "F.Cu")
		(at 390.056878 -28.309824 90)
		(property "Reference" "U104"
			(at -0.177546 2.754122 0)
			(unlocked yes)
			(layer "F.SilkS")
			(effects
				(font
					(size 0.7874 0.5842)
					(thickness 0.1524)
				)
				(justify left)
			)
		)
		(property "Value" ""
			(at 0 0 90)
			(layer "F.Fab")
			(effects
				(font
					(size 1.27 1.27)
				)
			)
		)
		(duplicate_pad_numbers_are_jumpers no)
		(fp_line
			(start 1.733296 -1.549908)
			(end 0.660908 -1.549908)
			(stroke
				(width 0.1524)
				(type default)
			)
			(layer "F.SilkS")
		)
		(fp_line
			(start 0.660908 -1.549908)
			(end 0 -0.889)
			(stroke
				(width 0.1524)
				(type default)
			)
			(layer "F.SilkS")
		)
		(fp_line
			(start -0.660908 -1.549908)
			(end -1.733296 -1.549908)
			(stroke
				(width 0.1524)
				(type default)
			)
			(layer "F.SilkS")
		)
		(fp_line
			(start -1.733296 -1.549908)
			(end -1.733296 1.549908)
			(stroke
				(width 0.1524)
				(type default)
			)
			(layer "F.SilkS")
		)
		(fp_line
			(start 0 -0.889)
			(end -0.660908 -1.549908)
			(stroke
				(width 0.1524)
				(type default)
			)
			(layer "F.SilkS")
		)
		(fp_line
			(start 1.733296 1.549908)
			(end 1.733296 -1.549908)
			(stroke
				(width 0.1524)
				(type default)
			)
			(layer "F.SilkS")
		)
		(fp_line
			(start -1.733296 1.549908)
			(end 1.733296 1.549908)
			(stroke
				(width 0.1524)
				(type default)
			)
			(layer "F.SilkS")
		)
		(fp_poly
			(pts
				(xy -1.227836 -2.218436) (xy -1.481836 -1.710436) (xy -1.735836 -2.218436)
			)
			(stroke
				(width 0)
				(type default)
			)
			(fill yes)
			(layer "F.SilkS")
		)
		(fp_line
			(start 0.849884 -1.549908)
			(end -0.849884 -1.549908)
			(stroke
				(width 0.1)
				(type default)
			)
			(layer "F.Fab")
		)
		(fp_line
			(start -0.849884 -1.549908)
			(end -0.849884 1.549908)
			(stroke
				(width 0.1)
				(type default)
			)
			(layer "F.Fab")
		)
		(fp_line
			(start 0.849884 1.549908)
			(end 0.849884 -1.549908)
			(stroke
				(width 0.1)
				(type default)
			)
			(layer "F.Fab")
		)
		(fp_line
			(start -0.849884 1.549908)
			(end 0.849884 1.549908)
			(stroke
				(width 0.1)
				(type default)
			)
			(layer "F.Fab")
		)
		(fp_poly
			(pts
				(xy -2.4384 -1.20396) (xy -2.4384 -0.69596) (xy -1.9304 -0.94996)
			)
			(stroke
				(width 0)
				(type default)
			)
			(fill yes)
			(layer "F.Fab")
		)
		(pad "1" smd rect
			(at -1.199896 -0.94996)
			(size 0.5588 0.8128)
			(layers "F.Cu" "F.Mask" "F.Paste")
			(net "NC_U104_NC1")
		)
		(pad "2" smd rect
			(at -1.199896 0)
			(size 0.5588 0.8128)
			(layers "F.Cu" "F.Mask" "F.Paste")
			(net "FM_SYS_THROTTLE_R_N")
		)
		(pad "3" smd rect
			(at -1.199896 0.94996)
			(size 0.5588 0.8128)
			(layers "F.Cu" "F.Mask" "F.Paste")
			(net "GND")
		)
		(pad "4" smd rect
			(at 1.199896 0.94996)
			(size 0.5588 0.8128)
			(layers "F.Cu" "F.Mask" "F.Paste")
			(net "OCP_SFF_PWRBRK_BUFF_N")
		)
		(pad "5" smd rect
			(at 1.199896 -0.94996)
			(size 0.5588 0.8128)
			(layers "F.Cu" "F.Mask" "F.Paste")
			(net "P3V3_AUX")
		)
	)
)
